(kicad_pcb
	(version 20241229)
	(generator "pcbnew")
	(generator_version "9.0")
	(general
		(thickness 1.711)
		(legacy_teardrops no)
	)
	(paper "A4")
	(title_block
		(title "Antmicro Baseboard for Jetson AGX Thor")
		(date "2026-02-18")
		(rev "1.1.0")
		(company "Antmicro Ltd")
		(comment 1 "www.antmicro.com")
		(comment 9 "footprints 241-245 of 1170")
	)
	(layers
		(0 "F.Cu" signal)
		(4 "In1.Cu" signal)
		(6 "In2.Cu" signal)
		(8 "In3.Cu" signal)
		(10 "In4.Cu" jumper)
		(12 "In5.Cu" signal)
		(14 "In6.Cu" signal)
		(16 "In7.Cu" signal)
		(18 "In8.Cu" signal)
		(2 "B.Cu" signal)
		(9 "F.Adhes" user "F.Adhesive")
		(11 "B.Adhes" user "B.Adhesive")
		(13 "F.Paste" user)
		(15 "B.Paste" user)
		(5 "F.SilkS" user "F.Silkscreen")
		(7 "B.SilkS" user "B.Silkscreen")
		(1 "F.Mask" user)
		(3 "B.Mask" user)
		(17 "Dwgs.User" user "User.Drawings")
		(19 "Cmts.User" user "User.Comments")
		(21 "Eco1.User" user "User.Eco1")
		(23 "Eco2.User" user "User.Eco2")
		(25 "Edge.Cuts" user)
		(27 "Margin" user)
		(31 "F.CrtYd" user "F.Courtyard")
		(29 "B.CrtYd" user "B.Courtyard")
		(35 "F.Fab" user)
		(33 "B.Fab" user)
	)
	(footprint "antmicro-footprints:C_0402_1005Metric"
		(layer "F.Cu")
		(at 184.019468 142.19 -90)
		(descr "Capacitor SMD 0402")
		(tags "capacitor SMD 0402")
		(property "Reference" "C54"
			(at -1.29 -0.680532 90)
			(layer "F.SilkS")
			(effects
				(font
					(size 0.7 0.7)
					(thickness 0.15)
				)
				(justify right top)
			)
		)
		(property "Value" "C_1u_0402"
			(at -1.022927 2.155213 90)
			(layer "F.Fab")
			(effects
				(font
					(size 0.7 0.7)
					(thickness 0.15)
				)
				(justify right top)
			)
		)
		(property "Datasheet" "https://product.tdk.com/en/search/capacitor/ceramic/mlcc/info?part_no=C1005X6S1A105K050BC"
			(at 0 0 90)
			(layer "F.Fab")
			(hide yes)
			(effects
				(font
					(size 1.27 1.27)
					(thickness 0.15)
				)
			)
		)
		(property "Description" "SMD Multilayer Ceramic Capacitor, 1 µF, 10 V, 0402 [1005 Metric], ± 10%, X6S, C"
			(at 0 0 90)
			(layer "F.Fab")
			(hide yes)
			(effects
				(font
					(size 1.27 1.27)
					(thickness 0.15)
				)
			)
		)
		(property "Manufacturer" "TDK"
			(at 0 0 270)
			(unlocked yes)
			(layer "F.Fab")
			(hide yes)
			(effects
				(font
					(size 1 1)
					(thickness 0.15)
				)
			)
		)
		(property "MPN" "C1005X6S1A105K050BC"
			(at 0 0 270)
			(unlocked yes)
			(layer "F.Fab")
			(hide yes)
			(effects
				(font
					(size 1 1)
					(thickness 0.15)
				)
			)
		)
		(property "Val" "1u"
			(at 0 0 270)
			(unlocked yes)
			(layer "F.Fab")
			(hide yes)
			(effects
				(font
					(size 1 1)
					(thickness 0.15)
				)
			)
		)
		(property "License" "Apache-2.0"
			(at 0 0 270)
			(unlocked yes)
			(layer "F.Fab")
			(hide yes)
			(effects
				(font
					(size 1 1)
					(thickness 0.15)
				)
			)
		)
		(property "Author" "Antmicro"
			(at 0 0 270)
			(unlocked yes)
			(layer "F.Fab")
			(hide yes)
			(effects
				(font
					(size 1 1)
					(thickness 0.15)
				)
			)
		)
		(property "Voltage" ""
			(at 0 0 270)
			(unlocked yes)
			(layer "F.Fab")
			(hide yes)
			(effects
				(font
					(size 1 1)
					(thickness 0.15)
				)
			)
		)
		(property "Dielectric" ""
			(at 0 0 270)
			(unlocked yes)
			(layer "F.Fab")
			(hide yes)
			(effects
				(font
					(size 1 1)
					(thickness 0.15)
				)
			)
		)
		(sheetname "/DCDC/")
		(sheetfile "dcdc.kicad_sch")
		(attr smd)
		(fp_rect
			(start -0.925 -0.47)
			(end 0.925 0.47)
			(stroke
				(width 0.05)
				(type default)
			)
			(fill no)
			(layer "F.CrtYd")
		)
		(fp_line
			(start -0.494 0.248)
			(end -0.494 -0.25)
			(stroke
				(width 0.15)
				(type solid)
			)
			(layer "F.Fab")
		)
		(fp_line
			(start 0.504 0.248)
			(end -0.494 0.248)
			(stroke
				(width 0.15)
				(type solid)
			)
			(layer "F.Fab")
		)
		(fp_line
			(start -0.494 -0.25)
			(end 0.504 -0.25)
			(stroke
				(width 0.15)
				(type solid)
			)
			(layer "F.Fab")
		)
		(fp_line
			(start 0.504 -0.25)
			(end 0.504 0.248)
			(stroke
				(width 0.15)
				(type solid)
			)
			(layer "F.Fab")
		)
		(fp_text user "${REFERENCE}"
			(at -0.939 4.599 90)
			(layer "F.Fab")
			(effects
				(font
					(size 0.7 0.7)
					(thickness 0.15)
				)
				(justify right top)
			)
		)
		(fp_text user "Author: Antmicro"
			(at -0.939 3.399 90)
			(layer "F.Fab")
			(effects
				(font
					(size 0.7 0.7)
					(thickness 0.15)
				)
				(justify right top)
			)
		)
		(fp_text user "License: Apache-2.0"
			(at -0.939 5.799 90)
			(layer "F.Fab")
			(effects
				(font
					(size 0.7 0.7)
					(thickness 0.15)
				)
				(justify right top)
			)
		)
		(pad "1" smd roundrect
			(at -0.48 0 270)
			(size 0.59 0.64)
			(layers "F.Cu" "F.Mask" "F.Paste")
			(roundrect_rratio 0.25)
			(net 1 "GND")
			(pintype "passive")
		)
		(pad "2" smd roundrect
			(at 0.48 0 270)
			(size 0.59 0.64)
			(layers "F.Cu" "F.Mask" "F.Paste")
			(roundrect_rratio 0.25)
			(net 20 "/DCDC/12V_VDD")
			(pintype "passive")
		)
	)
	(footprint "antmicro-footprints:R_0402_1005Metric"
		(layer "F.Cu")
		(at 190.3 122.6 90)
		(descr "Resistor SMD 0402")
		(tags "resistor SMD 0402")
		(property "Reference" "R378"
			(at 7.1 -2.4 90)
			(layer "F.SilkS")
			(effects
				(font
					(size 0.7 0.7)
					(thickness 0.15)
				)
				(justify left bottom)
			)
		)
		(property "Value" "R_0R_0402"
			(at -1.011843 1.772047 90)
			(layer "F.Fab")
			(effects
				(font
					(size 0.7 0.7)
					(thickness 0.15)
				)
				(justify left bottom)
			)
		)
		(property "Datasheet" "https://industrial.panasonic.com/cdbs/www-data/pdf/RDA0000/AOA0000C301.pdf"
			(at 0 0 90)
			(layer "F.Fab")
			(hide yes)
			(effects
				(font
					(size 1.27 1.27)
					(thickness 0.15)
				)
			)
		)
		(property "Description" "SMD Chip Resistor, Jumper, 0 ohm, 100 mW, 0402 [1005 Metric], Thick Film, General Purpose"
			(at 0 0 90)
			(layer "F.Fab")
			(hide yes)
			(effects
				(font
					(size 1.27 1.27)
					(thickness 0.15)
				)
			)
		)
		(property "MPN" "ERJ2GE0R00X"
			(at 0 0 90)
			(unlocked yes)
			(layer "F.Fab")
			(hide yes)
			(effects
				(font
					(size 1 1)
					(thickness 0.15)
				)
			)
		)
		(property "Manufacturer" "Panasonic"
			(at 0 0 90)
			(unlocked yes)
			(layer "F.Fab")
			(hide yes)
			(effects
				(font
					(size 1 1)
					(thickness 0.15)
				)
			)
		)
		(property "License" "Apache-2.0"
			(at 0 0 90)
			(unlocked yes)
			(layer "F.Fab")
			(hide yes)
			(effects
				(font
					(size 1 1)
					(thickness 0.15)
				)
			)
		)
		(property "Author" "Antmicro"
			(at 0 0 90)
			(unlocked yes)
			(layer "F.Fab")
			(hide yes)
			(effects
				(font
					(size 1 1)
					(thickness 0.15)
				)
			)
		)
		(property "Val" "0R"
			(at 0 0 90)
			(unlocked yes)
			(layer "F.Fab")
			(hide yes)
			(effects
				(font
					(size 1 1)
					(thickness 0.15)
				)
			)
		)
		(property "Tolerance" "~"
			(at 0 0 90)
			(unlocked yes)
			(layer "F.Fab")
			(hide yes)
			(effects
				(font
					(size 1 1)
					(thickness 0.15)
				)
			)
		)
		(property "Current" "1A"
			(at 0 0 90)
			(unlocked yes)
			(layer "F.Fab")
			(hide yes)
			(effects
				(font
					(size 1 1)
					(thickness 0.15)
				)
			)
		)
		(sheetname "/USB Hub/")
		(sheetfile "usb_hub.kicad_sch")
		(attr smd exclude_from_pos_files exclude_from_bom dnp)
		(fp_rect
			(start -0.925 -0.47)
			(end 0.925 0.47)
			(stroke
				(width 0.05)
				(type default)
			)
			(fill no)
			(layer "F.CrtYd")
		)
		(fp_rect
			(start -0.5 -0.25)
			(end 0.5 0.25)
			(stroke
				(width 0.15)
				(type solid)
			)
			(fill no)
			(layer "F.Fab")
		)
		(fp_text user "Author: Antmicro"
			(at -0.95 4.169 90)
			(layer "F.Fab")
			(effects
				(font
					(size 0.7 0.7)
					(thickness 0.15)
				)
				(justify left bottom)
			)
		)
		(fp_text user "License: Apache-2.0"
			(at -0.95 5.169 90)
			(layer "F.Fab")
			(effects
				(font
					(size 0.7 0.7)
					(thickness 0.15)
				)
				(justify left bottom)
			)
		)
		(fp_text user "${REFERENCE}"
			(at -0.95 3.168 90)
			(layer "F.Fab")
			(effects
				(font
					(size 0.7 0.7)
					(thickness 0.15)
				)
				(justify left bottom)
			)
		)
		(pad "1" smd roundrect
			(at -0.48 0 90)
			(size 0.59 0.64)
			(layers "F.Cu" "F.Mask" "F.Paste")
			(roundrect_rratio 0.25)
			(net 922 "/USB Hub/HUB_SPI_D1")
			(pintype "passive")
		)
		(pad "2" smd roundrect
			(at 0.48 0 90)
			(size 0.59 0.64)
			(layers "F.Cu" "F.Mask" "F.Paste")
			(roundrect_rratio 0.25)
			(net 926 "/USB Debug, PD/SPI_{HUB_DEBUG}.MOSI")
			(pintype "passive")
		)
	)
	(footprint "antmicro-footprints:R_0402_1005Metric"
		(layer "F.Cu")
		(at 88 60.5 180)
		(descr "Resistor SMD 0402")
		(tags "resistor SMD 0402")
		(property "Reference" "R289"
			(at 16.3 -8.8 0)
			(layer "F.SilkS")
			(effects
				(font
					(size 0.7 0.7)
					(thickness 0.15)
				)
				(justify right top)
			)
		)
		(property "Value" "R_10k_0402"
			(at -1.011843 1.772047 0)
			(layer "F.Fab")
			(effects
				(font
					(size 0.7 0.7)
					(thickness 0.15)
				)
				(justify right top)
			)
		)
		(property "Datasheet" "https://www.bourns.com/docs/product-datasheets/cr.pdf"
			(at 0 0 0)
			(layer "F.Fab")
			(hide yes)
			(effects
				(font
					(size 1.27 1.27)
					(thickness 0.15)
				)
			)
		)
		(property "Description" "SMD Chip Resistor, 10 kohm, ± 1%, 62.5 mW, 0402 [1005 Metric], Thick Film, General Purpose"
			(at 0 0 0)
			(layer "F.Fab")
			(hide yes)
			(effects
				(font
					(size 1.27 1.27)
					(thickness 0.15)
				)
			)
		)
		(property "MPN" "CR0402-FX-1002GLF"
			(at 0 0 180)
			(unlocked yes)
			(layer "F.Fab")
			(hide yes)
			(effects
				(font
					(size 1 1)
					(thickness 0.15)
				)
			)
		)
		(property "Manufacturer" "Bourns"
			(at 0 0 180)
			(unlocked yes)
			(layer "F.Fab")
			(hide yes)
			(effects
				(font
					(size 1 1)
					(thickness 0.15)
				)
			)
		)
		(property "License" "Apache-2.0"
			(at 0 0 180)
			(unlocked yes)
			(layer "F.Fab")
			(hide yes)
			(effects
				(font
					(size 1 1)
					(thickness 0.15)
				)
			)
		)
		(property "Author" "Antmicro"
			(at 0 0 180)
			(unlocked yes)
			(layer "F.Fab")
			(hide yes)
			(effects
				(font
					(size 1 1)
					(thickness 0.15)
				)
			)
		)
		(property "Val" "10k"
			(at 0 0 180)
			(unlocked yes)
			(layer "F.Fab")
			(hide yes)
			(effects
				(font
					(size 1 1)
					(thickness 0.15)
				)
			)
		)
		(property "Tolerance" "1%"
			(at 0 0 180)
			(unlocked yes)
			(layer "F.Fab")
			(hide yes)
			(effects
				(font
					(size 1 1)
					(thickness 0.15)
				)
			)
		)
		(property "Current" "1A"
			(at 0 0 180)
			(unlocked yes)
			(layer "F.Fab")
			(hide yes)
			(effects
				(font
					(size 1 1)
					(thickness 0.15)
				)
			)
		)
		(sheetname "/SoM_Power/")
		(sheetfile "som_power.kicad_sch")
		(attr smd exclude_from_pos_files exclude_from_bom dnp)
		(fp_rect
			(start -0.925 -0.47)
			(end 0.925 0.47)
			(stroke
				(width 0.05)
				(type default)
			)
			(fill no)
			(layer "F.CrtYd")
		)
		(fp_rect
			(start -0.5 -0.25)
			(end 0.5 0.25)
			(stroke
				(width 0.15)
				(type solid)
			)
			(fill no)
			(layer "F.Fab")
		)
		(fp_text user "License: Apache-2.0"
			(at -0.95 5.169 0)
			(layer "F.Fab")
			(effects
				(font
					(size 0.7 0.7)
					(thickness 0.15)
				)
				(justify right top)
			)
		)
		(fp_text user "${REFERENCE}"
			(at -0.95 3.168 0)
			(layer "F.Fab")
			(effects
				(font
					(size 0.7 0.7)
					(thickness 0.15)
				)
				(justify right top)
			)
		)
		(fp_text user "Author: Antmicro"
			(at -0.95 4.169 0)
			(layer "F.Fab")
			(effects
				(font
					(size 0.7 0.7)
					(thickness 0.15)
				)
				(justify right top)
			)
		)
		(pad "1" smd roundrect
			(at -0.48 0 180)
			(size 0.59 0.64)
			(layers "F.Cu" "F.Mask" "F.Paste")
			(roundrect_rratio 0.25)
			(net 1027 "Net-(U70-~{CLR})")
			(pintype "passive")
		)
		(pad "2" smd roundrect
			(at 0.48 0 180)
			(size 0.59 0.64)
			(layers "F.Cu" "F.Mask" "F.Paste")
			(roundrect_rratio 0.25)
			(net 491 "+5V_AON")
			(pintype "passive")
		)
	)
	(footprint "antmicro-footprints:C_0603_1608Metric_EIA"
		(layer "F.Cu")
		(at 173.5 130.18 -90)
		(descr "Capacitor SMD 0603, IPC-7351 Density Level A")
		(tags "Capacitor 0603")
		(property "Reference" "C67"
			(at -4.28 9 90)
			(layer "F.SilkS")
			(effects
				(font
					(size 0.7 0.7)
					(thickness 0.15)
				)
				(justify right top)
			)
		)
		(property "Value" "C_22u_16V_0603"
			(at -1.42757 1.770288 90)
			(layer "F.Fab")
			(effects
				(font
					(size 0.7 0.7)
					(thickness 0.15)
				)
				(justify right top)
			)
		)
		(property "Datasheet" "https://product.samsungsem.com/mlcc/CL10A226MO7JZN.do"
			(at 0 0 90)
			(layer "F.Fab")
			(hide yes)
			(effects
				(font
					(size 1.27 1.27)
					(thickness 0.15)
				)
			)
		)
		(property "Description" "SMD Multilayer Ceramic Capacitor"
			(at 0 0 90)
			(layer "F.Fab")
			(hide yes)
			(effects
				(font
					(size 1.27 1.27)
					(thickness 0.15)
				)
			)
		)
		(property "Manufacturer" "Samsung Electro-Mechanics"
			(at 0 0 270)
			(unlocked yes)
			(layer "F.Fab")
			(hide yes)
			(effects
				(font
					(size 1 1)
					(thickness 0.15)
				)
			)
		)
		(property "MPN" "CL10A226MO7JZNC"
			(at 0 0 270)
			(unlocked yes)
			(layer "F.Fab")
			(hide yes)
			(effects
				(font
					(size 1 1)
					(thickness 0.15)
				)
			)
		)
		(property "Val" "22u"
			(at 0 0 270)
			(unlocked yes)
			(layer "F.Fab")
			(hide yes)
			(effects
				(font
					(size 1 1)
					(thickness 0.15)
				)
			)
		)
		(property "License" "Apache-2.0"
			(at 0 0 270)
			(unlocked yes)
			(layer "F.Fab")
			(hide yes)
			(effects
				(font
					(size 1 1)
					(thickness 0.15)
				)
			)
		)
		(property "Author" "Antmicro"
			(at 0 0 270)
			(unlocked yes)
			(layer "F.Fab")
			(hide yes)
			(effects
				(font
					(size 1 1)
					(thickness 0.15)
				)
			)
		)
		(property "Voltage" "16V"
			(at 0 0 270)
			(unlocked yes)
			(layer "F.Fab")
			(hide yes)
			(effects
				(font
					(size 1 1)
					(thickness 0.15)
				)
			)
		)
		(property "Dielectric" ""
			(at 0 0 270)
			(unlocked yes)
			(layer "F.Fab")
			(hide yes)
			(effects
				(font
					(size 1 1)
					(thickness 0.15)
				)
			)
		)
		(sheetname "/DCDC/")
		(sheetfile "dcdc.kicad_sch")
		(attr smd)
		(fp_line
			(start -0.15 0.55)
			(end 0.15 0.55)
			(stroke
				(width 0.15)
				(type solid)
			)
			(layer "F.SilkS")
		)
		(fp_line
			(start -0.15 -0.55)
			(end 0.15 -0.55)
			(stroke
				(width 0.15)
				(type solid)
			)
			(layer "F.SilkS")
		)
		(fp_rect
			(start -1.25 -0.65)
			(end 1.25 0.65)
			(stroke
				(width 0.05)
				(type solid)
			)
			(fill no)
			(layer "F.CrtYd")
		)
		(fp_rect
			(start -0.8 -0.45)
			(end 0.8 0.45)
			(stroke
				(width 0.15)
				(type solid)
			)
			(fill no)
			(layer "F.Fab")
		)
		(fp_text user "License: Apache-2.0"
			(at -1.682 5.895 90)
			(layer "F.Fab")
			(effects
				(font
					(size 0.7 0.7)
					(thickness 0.15)
				)
				(justify right top)
			)
		)
		(fp_text user "Author: Antmicro"
			(at -1.682 4.894 90)
			(layer "F.Fab")
			(effects
				(font
					(size 0.7 0.7)
					(thickness 0.15)
				)
				(justify right top)
			)
		)
		(fp_text user "${REFERENCE}"
			(at -1.682 3.895 90)
			(layer "F.Fab")
			(effects
				(font
					(size 0.7 0.7)
					(thickness 0.15)
				)
				(justify right top)
			)
		)
		(pad "1" smd roundrect
			(at -0.7 0 270)
			(size 0.8 1.1)
			(layers "F.Cu" "F.Mask" "F.Paste")
			(roundrect_rratio 0.2)
			(net 1 "GND")
			(pintype "passive")
		)
		(pad "2" smd roundrect
			(at 0.7 0 270)
			(size 0.8 1.1)
			(layers "F.Cu" "F.Mask" "F.Paste")
			(roundrect_rratio 0.2)
			(net 567 "/DCDC/3V3_OUT")
			(pintype "passive")
		)
	)
	(footprint "antmicro-footprints:Fiducial_1mm_Mask3mm"
		(layer "F.Cu")
		(at 211.23 58.44)
		(descr "Circular Fiducial, 1.5mm bare copper, 3mm soldermask opening")
		(tags "fiducial")
		(property "Reference" "FD4"
			(at -3.06 1.65 0)
			(layer "F.SilkS")
			(effects
				(font
					(size 0.7 0.7)
					(thickness 0.15)
				)
				(justify left bottom)
			)
		)
		(property "Value" "Fiducial_1mm_Mask3mm"
			(at 0 2.603 0)
			(layer "F.Fab")
			(effects
				(font
					(size 0.7 0.7)
					(thickness 0.15)
				)
				(justify left bottom)
			)
		)
		(property "Description" "Fiducial mask"
			(at 0 0 0)
			(layer "F.Fab")
			(hide yes)
			(effects
				(font
					(size 1.27 1.27)
					(thickness 0.15)
				)
			)
		)
		(property "Author" "Antmicro"
			(at 0 0 0)
			(unlocked yes)
			(layer "F.Fab")
			(hide yes)
			(effects
				(font
					(size 1 1)
					(thickness 0.15)
				)
			)
		)
		(property "License" "Apache-2.0"
			(at 0 0 0)
			(unlocked yes)
			(layer "F.Fab")
			(hide yes)
			(effects
				(font
					(size 1 1)
					(thickness 0.15)
				)
			)
		)
		(sheetname "/")
		(sheetfile "jetson-agx-thor-baseboard.kicad_sch")
		(attr exclude_from_pos_files exclude_from_bom)
		(fp_circle
			(center 0 0)
			(end 1.5 0)
			(stroke
				(width 0.05)
				(type solid)
			)
			(fill no)
			(layer "F.CrtYd")
		)
		(fp_circle
			(center 0 0)
			(end 1.5 0)
			(stroke
				(width 0.15)
				(type solid)
			)
			(fill no)
			(layer "F.Fab")
		)
		(fp_text user "Author: Antmicro"
			(at -1.25 5.803 0)
			(layer "F.Fab")
			(effects
				(font
					(size 0.7 0.7)
					(thickness 0.15)
				)
				(justify left bottom)
			)
		)
		(fp_text user "License: Apache-2.0"
			(at -1.25 7.003 0)
			(layer "F.Fab")
			(effects
				(font
					(size 0.7 0.7)
					(thickness 0.15)
				)
				(justify left bottom)
			)
		)
		(fp_text user "${REFERENCE}"
			(at -1.25 4.603 0)
			(layer "F.Fab")
			(effects
				(font
					(size 0.7 0.7)
					(thickness 0.15)
				)
				(justify left bottom)
			)
		)
		(pad "" smd circle
			(at 0 0)
			(size 1 1)
			(layers "F.Cu" "F.Mask")
			(solder_mask_margin 1)
			(clearance 1)
		)
	)
)
